(kicad_pcb
	(version 20260206)
	(generator "pcbnew")
	(generator_version "10.0")
	(general
		(thickness 1.6)
		(legacy_teardrops no)
	)
	(paper "A4")
	(title_block
		(title "01162023_DA0F0TEBIF0_F0T_Expander_BD_F_brd_V02_OCP.brd")
		(comment 1 "Grand Teton / footprints 529-535 of 9728")
	)
	(layers
		(0 "F.Cu" signal "TOP")
		(4 "In1.Cu" signal "GND")
		(6 "In2.Cu" signal "VCC")
		(8 "In3.Cu" signal "VCC1")
		(10 "In4.Cu" signal "GND1")
		(12 "In5.Cu" signal "IN1")
		(14 "In6.Cu" signal "GND2")
		(16 "In7.Cu" signal "IN2")
		(18 "In8.Cu" signal "GND3")
		(20 "In9.Cu" signal "IN3")
		(22 "In10.Cu" signal "GND4")
		(24 "In11.Cu" signal "IN4")
		(26 "In12.Cu" signal "GND5")
		(28 "In13.Cu" signal "IN5")
		(30 "In14.Cu" signal "GND6")
		(32 "In15.Cu" signal "IN6")
		(34 "In16.Cu" signal "GND7")
		(2 "B.Cu" signal "BOTTOM")
		(9 "F.Adhes" user "F.Adhesive")
		(11 "B.Adhes" user "B.Adhesive")
		(13 "F.Paste" user "Package Geometry/Pastemask Top")
		(15 "B.Paste" user "Package Geometry/Pastemask Bottom")
		(5 "F.SilkS" user "Ref Des/Silkscreen Top")
		(7 "B.SilkS" user "Ref Des/Silkscreen Bottom")
		(1 "F.Mask" user "Board Geometry/Soldermask Top")
		(3 "B.Mask" user "Board Geometry/Soldermask Bottom")
		(17 "Dwgs.User" user "User.Drawings")
		(19 "Cmts.User" user "User.Comments")
		(21 "Eco1.User" user "User.Eco1")
		(23 "Eco2.User" user "User.Eco2")
		(25 "Edge.Cuts" user "Board Geometry/Outline")
		(27 "Margin" user)
		(31 "F.CrtYd" user "Package Geometry/Place Bound Top")
		(29 "B.CrtYd" user "Package Geometry/Place Bound Bottom")
		(35 "F.Fab" user "Ref Des/Assembly Top")
		(33 "B.Fab" user "Ref Des/Assembly Bottom")
	)
	(footprint ""
		(layer "F.Cu")
		(at 235.476288 -97.258378 90)
		(property "Reference" "C2624"
			(at 0 0 90)
			(layer "F.SilkS")
			(hide yes)
			(effects
				(font
					(size 1.27 1.27)
				)
			)
		)
		(property "Value" ""
			(at 0 0 90)
			(layer "F.Fab")
			(effects
				(font
					(size 1.27 1.27)
				)
			)
		)
		(duplicate_pad_numbers_are_jumpers no)
		(fp_line
			(start 0.7874 -0.4064)
			(end 0.7874 0.4064)
			(stroke
				(width 0.1524)
				(type default)
			)
			(layer "F.SilkS")
		)
		(fp_line
			(start -0.7874 -0.4064)
			(end 0.7874 -0.4064)
			(stroke
				(width 0.1524)
				(type default)
			)
			(layer "F.SilkS")
		)
		(fp_line
			(start 0.7874 0.4064)
			(end -0.7874 0.4064)
			(stroke
				(width 0.1524)
				(type default)
			)
			(layer "F.SilkS")
		)
		(fp_line
			(start -0.7874 0.4064)
			(end -0.7874 -0.4064)
			(stroke
				(width 0.1524)
				(type default)
			)
			(layer "F.SilkS")
		)
		(fp_line
			(start -0.12065 -0.305054)
			(end -0.12065 -0.2794)
			(stroke
				(width 0.1)
				(type default)
			)
			(layer "F.Fab")
		)
		(fp_line
			(start -0.67945 -0.305054)
			(end -0.12065 -0.305054)
			(stroke
				(width 0.1)
				(type default)
			)
			(layer "F.Fab")
		)
		(fp_line
			(start 0.67945 -0.3048)
			(end 0.67945 0.3048)
			(stroke
				(width 0.1)
				(type default)
			)
			(layer "F.Fab")
		)
		(fp_line
			(start 0.12065 -0.3048)
			(end 0.67945 -0.3048)
			(stroke
				(width 0.1)
				(type default)
			)
			(layer "F.Fab")
		)
		(fp_line
			(start 0.12065 -0.2794)
			(end 0.12065 -0.3048)
			(stroke
				(width 0.1)
				(type default)
			)
			(layer "F.Fab")
		)
		(fp_line
			(start -0.12065 -0.2794)
			(end 0.12065 -0.2794)
			(stroke
				(width 0.1)
				(type default)
			)
			(layer "F.Fab")
		)
		(fp_line
			(start 0.120396 0.2794)
			(end -0.12065 0.2794)
			(stroke
				(width 0.1)
				(type default)
			)
			(layer "F.Fab")
		)
		(fp_line
			(start -0.12065 0.2794)
			(end -0.12065 0.3048)
			(stroke
				(width 0.1)
				(type default)
			)
			(layer "F.Fab")
		)
		(fp_line
			(start 0.67945 0.3048)
			(end 0.120396 0.3048)
			(stroke
				(width 0.1)
				(type default)
			)
			(layer "F.Fab")
		)
		(fp_line
			(start 0.120396 0.3048)
			(end 0.120396 0.2794)
			(stroke
				(width 0.1)
				(type default)
			)
			(layer "F.Fab")
		)
		(fp_line
			(start -0.12065 0.3048)
			(end -0.67945 0.3048)
			(stroke
				(width 0.1)
				(type default)
			)
			(layer "F.Fab")
		)
		(fp_line
			(start -0.67945 0.3048)
			(end -0.67945 -0.305054)
			(stroke
				(width 0.1)
				(type default)
			)
			(layer "F.Fab")
		)
		(pad "1" smd circle
			(at -0.40005 0 90)
			(size 0 0)
			(layers "F.Cu" "F.Mask" "F.Paste")
			(net "RST_PEX_USB_HUB_R_N")
		)
		(pad "2" smd circle
			(at 0.40005 0 90)
			(size 0 0)
			(layers "F.Cu" "F.Mask" "F.Paste")
			(net "GND")
		)
	)
	(footprint ""
		(layer "F.Cu")
		(at 168.378632 -350.098614 90)
		(property "Reference" "C2518"
			(at 0 0 90)
			(layer "F.SilkS")
			(hide yes)
			(effects
				(font
					(size 1.27 1.27)
				)
			)
		)
		(property "Value" ""
			(at 0 0 90)
			(layer "F.Fab")
			(effects
				(font
					(size 1.27 1.27)
				)
			)
		)
		(duplicate_pad_numbers_are_jumpers no)
		(fp_line
			(start 0.299974 -0.150114)
			(end 0.299974 0.150114)
			(stroke
				(width 0.1)
				(type default)
			)
			(layer "F.Fab")
		)
		(fp_line
			(start -0.299974 -0.150114)
			(end 0.299974 -0.150114)
			(stroke
				(width 0.1)
				(type default)
			)
			(layer "F.Fab")
		)
		(fp_line
			(start 0.299974 0.150114)
			(end -0.299974 0.150114)
			(stroke
				(width 0.1)
				(type default)
			)
			(layer "F.Fab")
		)
		(fp_line
			(start -0.299974 0.150114)
			(end -0.299974 -0.150114)
			(stroke
				(width 0.1)
				(type default)
			)
			(layer "F.Fab")
		)
		(pad "1" smd rect
			(at -0.2667 0 90)
			(size 0.3048 0.381)
			(layers "F.Cu" "F.Mask" "F.Paste")
			(net "P5E_PEX1_STN4_TX_DP<76>")
		)
		(pad "2" smd rect
			(at 0.2667 0 90)
			(size 0.3048 0.381)
			(layers "F.Cu" "F.Mask" "F.Paste")
			(net "P5E_PEX1_STN4_TX_C_DP<76>")
		)
	)
	(footprint ""
		(layer "F.Cu")
		(at 76.48194 -37.025072)
		(property "Reference" "R5657"
			(at 0 0 0)
			(layer "F.SilkS")
			(hide yes)
			(effects
				(font
					(size 1.27 1.27)
				)
			)
		)
		(property "Value" ""
			(at 0 0 0)
			(layer "F.Fab")
			(effects
				(font
					(size 1.27 1.27)
				)
			)
		)
		(duplicate_pad_numbers_are_jumpers no)
		(fp_line
			(start -0.7874 -0.4064)
			(end 0.7874 -0.4064)
			(stroke
				(width 0.1524)
				(type default)
			)
			(layer "F.SilkS")
		)
		(fp_line
			(start -0.7874 0.4064)
			(end -0.7874 -0.4064)
			(stroke
				(width 0.1524)
				(type default)
			)
			(layer "F.SilkS")
		)
		(fp_line
			(start 0.7874 -0.4064)
			(end 0.7874 0.4064)
			(stroke
				(width 0.1524)
				(type default)
			)
			(layer "F.SilkS")
		)
		(fp_line
			(start 0.7874 0.4064)
			(end -0.7874 0.4064)
			(stroke
				(width 0.1524)
				(type default)
			)
			(layer "F.SilkS")
		)
		(fp_line
			(start -0.67945 -0.305054)
			(end -0.12065 -0.305054)
			(stroke
				(width 0.1)
				(type default)
			)
			(layer "F.Fab")
		)
		(fp_line
			(start -0.67945 0.3048)
			(end -0.67945 -0.305054)
			(stroke
				(width 0.1)
				(type default)
			)
			(layer "F.Fab")
		)
		(fp_line
			(start -0.12065 -0.305054)
			(end -0.12065 -0.2794)
			(stroke
				(width 0.1)
				(type default)
			)
			(layer "F.Fab")
		)
		(fp_line
			(start -0.12065 -0.2794)
			(end 0.12065 -0.2794)
			(stroke
				(width 0.1)
				(type default)
			)
			(layer "F.Fab")
		)
		(fp_line
			(start -0.12065 0.2794)
			(end -0.12065 0.3048)
			(stroke
				(width 0.1)
				(type default)
			)
			(layer "F.Fab")
		)
		(fp_line
			(start -0.12065 0.3048)
			(end -0.67945 0.3048)
			(stroke
				(width 0.1)
				(type default)
			)
			(layer "F.Fab")
		)
		(fp_line
			(start 0.120396 0.2794)
			(end -0.12065 0.2794)
			(stroke
				(width 0.1)
				(type default)
			)
			(layer "F.Fab")
		)
		(fp_line
			(start 0.120396 0.3048)
			(end 0.120396 0.2794)
			(stroke
				(width 0.1)
				(type default)
			)
			(layer "F.Fab")
		)
		(fp_line
			(start 0.12065 -0.3048)
			(end 0.67945 -0.3048)
			(stroke
				(width 0.1)
				(type default)
			)
			(layer "F.Fab")
		)
		(fp_line
			(start 0.12065 -0.2794)
			(end 0.12065 -0.3048)
			(stroke
				(width 0.1)
				(type default)
			)
			(layer "F.Fab")
		)
		(fp_line
			(start 0.67945 -0.3048)
			(end 0.67945 0.3048)
			(stroke
				(width 0.1)
				(type default)
			)
			(layer "F.Fab")
		)
		(fp_line
			(start 0.67945 0.3048)
			(end 0.120396 0.3048)
			(stroke
				(width 0.1)
				(type default)
			)
			(layer "F.Fab")
		)
		(pad "1" smd circle
			(at -0.40005 0)
			(size 0 0)
			(layers "F.Cu" "F.Mask" "F.Paste")
			(net "RST_SMB_SSD_R_N")
		)
		(pad "2" smd circle
			(at 0.40005 0)
			(size 0 0)
			(layers "F.Cu" "F.Mask" "F.Paste")
			(net "RST_SMB_SSD3_N")
		)
	)
	(footprint ""
		(layer "F.Cu")
		(at 314.915042 -59.546236 90)
		(property "Reference" "C2900"
			(at 0 0 90)
			(layer "F.SilkS")
			(hide yes)
			(effects
				(font
					(size 1.27 1.27)
				)
			)
		)
		(property "Value" ""
			(at 0 0 90)
			(layer "F.Fab")
			(effects
				(font
					(size 1.27 1.27)
				)
			)
		)
		(duplicate_pad_numbers_are_jumpers no)
		(fp_line
			(start 0.7874 -0.4064)
			(end 0.7874 0.4064)
			(stroke
				(width 0.1524)
				(type default)
			)
			(layer "F.SilkS")
		)
		(fp_line
			(start -0.7874 -0.4064)
			(end 0.7874 -0.4064)
			(stroke
				(width 0.1524)
				(type default)
			)
			(layer "F.SilkS")
		)
		(fp_line
			(start 0.7874 0.4064)
			(end -0.7874 0.4064)
			(stroke
				(width 0.1524)
				(type default)
			)
			(layer "F.SilkS")
		)
		(fp_line
			(start -0.7874 0.4064)
			(end -0.7874 -0.4064)
			(stroke
				(width 0.1524)
				(type default)
			)
			(layer "F.SilkS")
		)
		(fp_line
			(start -0.12065 -0.305054)
			(end -0.12065 -0.2794)
			(stroke
				(width 0.1)
				(type default)
			)
			(layer "F.Fab")
		)
		(fp_line
			(start -0.67945 -0.305054)
			(end -0.12065 -0.305054)
			(stroke
				(width 0.1)
				(type default)
			)
			(layer "F.Fab")
		)
		(fp_line
			(start 0.67945 -0.3048)
			(end 0.67945 0.3048)
			(stroke
				(width 0.1)
				(type default)
			)
			(layer "F.Fab")
		)
		(fp_line
			(start 0.12065 -0.3048)
			(end 0.67945 -0.3048)
			(stroke
				(width 0.1)
				(type default)
			)
			(layer "F.Fab")
		)
		(fp_line
			(start 0.12065 -0.2794)
			(end 0.12065 -0.3048)
			(stroke
				(width 0.1)
				(type default)
			)
			(layer "F.Fab")
		)
		(fp_line
			(start -0.12065 -0.2794)
			(end 0.12065 -0.2794)
			(stroke
				(width 0.1)
				(type default)
			)
			(layer "F.Fab")
		)
		(fp_line
			(start 0.120396 0.2794)
			(end -0.12065 0.2794)
			(stroke
				(width 0.1)
				(type default)
			)
			(layer "F.Fab")
		)
		(fp_line
			(start -0.12065 0.2794)
			(end -0.12065 0.3048)
			(stroke
				(width 0.1)
				(type default)
			)
			(layer "F.Fab")
		)
		(fp_line
			(start 0.67945 0.3048)
			(end 0.120396 0.3048)
			(stroke
				(width 0.1)
				(type default)
			)
			(layer "F.Fab")
		)
		(fp_line
			(start 0.120396 0.3048)
			(end 0.120396 0.2794)
			(stroke
				(width 0.1)
				(type default)
			)
			(layer "F.Fab")
		)
		(fp_line
			(start -0.12065 0.3048)
			(end -0.67945 0.3048)
			(stroke
				(width 0.1)
				(type default)
			)
			(layer "F.Fab")
		)
		(fp_line
			(start -0.67945 0.3048)
			(end -0.67945 -0.305054)
			(stroke
				(width 0.1)
				(type default)
			)
			(layer "F.Fab")
		)
		(pad "1" smd circle
			(at -0.40005 0 90)
			(size 0 0)
			(layers "F.Cu" "F.Mask" "F.Paste")
			(net "SSD11_AUX_P3V3_EN_R")
		)
		(pad "2" smd circle
			(at 0.40005 0 90)
			(size 0 0)
			(layers "F.Cu" "F.Mask" "F.Paste")
			(net "GND")
		)
	)
	(footprint ""
		(layer "F.Cu")
		(at 32.411416 -299.645832 -90)
		(property "Reference" "R4559"
			(at 0 0 270)
			(layer "F.SilkS")
			(hide yes)
			(effects
				(font
					(size 1.27 1.27)
				)
			)
		)
		(property "Value" ""
			(at 0 0 270)
			(layer "F.Fab")
			(effects
				(font
					(size 1.27 1.27)
				)
			)
		)
		(duplicate_pad_numbers_are_jumpers no)
		(fp_line
			(start -0.7874 0.4064)
			(end -0.7874 -0.4064)
			(stroke
				(width 0.1524)
				(type default)
			)
			(layer "F.SilkS")
		)
		(fp_line
			(start 0.7874 0.4064)
			(end -0.7874 0.4064)
			(stroke
				(width 0.1524)
				(type default)
			)
			(layer "F.SilkS")
		)
		(fp_line
			(start -0.7874 -0.4064)
			(end 0.7874 -0.4064)
			(stroke
				(width 0.1524)
				(type default)
			)
			(layer "F.SilkS")
		)
		(fp_line
			(start 0.7874 -0.4064)
			(end 0.7874 0.4064)
			(stroke
				(width 0.1524)
				(type default)
			)
			(layer "F.SilkS")
		)
		(fp_line
			(start -0.67945 0.3048)
			(end -0.67945 -0.305054)
			(stroke
				(width 0.1)
				(type default)
			)
			(layer "F.Fab")
		)
		(fp_line
			(start -0.12065 0.3048)
			(end -0.67945 0.3048)
			(stroke
				(width 0.1)
				(type default)
			)
			(layer "F.Fab")
		)
		(fp_line
			(start 0.120396 0.3048)
			(end 0.120396 0.2794)
			(stroke
				(width 0.1)
				(type default)
			)
			(layer "F.Fab")
		)
		(fp_line
			(start 0.67945 0.3048)
			(end 0.120396 0.3048)
			(stroke
				(width 0.1)
				(type default)
			)
			(layer "F.Fab")
		)
		(fp_line
			(start -0.12065 0.2794)
			(end -0.12065 0.3048)
			(stroke
				(width 0.1)
				(type default)
			)
			(layer "F.Fab")
		)
		(fp_line
			(start 0.120396 0.2794)
			(end -0.12065 0.2794)
			(stroke
				(width 0.1)
				(type default)
			)
			(layer "F.Fab")
		)
		(fp_line
			(start -0.12065 -0.2794)
			(end 0.12065 -0.2794)
			(stroke
				(width 0.1)
				(type default)
			)
			(layer "F.Fab")
		)
		(fp_line
			(start 0.12065 -0.2794)
			(end 0.12065 -0.3048)
			(stroke
				(width 0.1)
				(type default)
			)
			(layer "F.Fab")
		)
		(fp_line
			(start 0.12065 -0.3048)
			(end 0.67945 -0.3048)
			(stroke
				(width 0.1)
				(type default)
			)
			(layer "F.Fab")
		)
		(fp_line
			(start 0.67945 -0.3048)
			(end 0.67945 0.3048)
			(stroke
				(width 0.1)
				(type default)
			)
			(layer "F.Fab")
		)
		(fp_line
			(start -0.67945 -0.305054)
			(end -0.12065 -0.305054)
			(stroke
				(width 0.1)
				(type default)
			)
			(layer "F.Fab")
		)
		(fp_line
			(start -0.12065 -0.305054)
			(end -0.12065 -0.2794)
			(stroke
				(width 0.1)
				(type default)
			)
			(layer "F.Fab")
		)
		(pad "1" smd circle
			(at -0.40005 0 270)
			(size 0 0)
			(layers "F.Cu" "F.Mask" "F.Paste")
			(net "PCEPLL1_VDDA18_PEX0")
		)
		(pad "2" smd circle
			(at 0.40005 0 270)
			(size 0 0)
			(layers "F.Cu" "F.Mask" "F.Paste")
			(net "PCEPLL1_VDDA18_PEX0_R")
		)
	)
	(footprint ""
		(layer "F.Cu")
		(at 223.889316 -257.975862 -90)
		(property "Reference" "R6493"
			(at 0 0 270)
			(layer "F.SilkS")
			(hide yes)
			(effects
				(font
					(size 1.27 1.27)
				)
			)
		)
		(property "Value" ""
			(at 0 0 270)
			(layer "F.Fab")
			(effects
				(font
					(size 1.27 1.27)
				)
			)
		)
		(duplicate_pad_numbers_are_jumpers no)
		(fp_line
			(start -0.7874 0.4064)
			(end -0.7874 -0.4064)
			(stroke
				(width 0.1524)
				(type default)
			)
			(layer "F.SilkS")
		)
		(fp_line
			(start 0.7874 0.4064)
			(end -0.7874 0.4064)
			(stroke
				(width 0.1524)
				(type default)
			)
			(layer "F.SilkS")
		)
		(fp_line
			(start -0.7874 -0.4064)
			(end 0.7874 -0.4064)
			(stroke
				(width 0.1524)
				(type default)
			)
			(layer "F.SilkS")
		)
		(fp_line
			(start 0.7874 -0.4064)
			(end 0.7874 0.4064)
			(stroke
				(width 0.1524)
				(type default)
			)
			(layer "F.SilkS")
		)
		(fp_line
			(start -0.67945 0.3048)
			(end -0.67945 -0.305054)
			(stroke
				(width 0.1)
				(type default)
			)
			(layer "F.Fab")
		)
		(fp_line
			(start -0.12065 0.3048)
			(end -0.67945 0.3048)
			(stroke
				(width 0.1)
				(type default)
			)
			(layer "F.Fab")
		)
		(fp_line
			(start 0.120396 0.3048)
			(end 0.120396 0.2794)
			(stroke
				(width 0.1)
				(type default)
			)
			(layer "F.Fab")
		)
		(fp_line
			(start 0.67945 0.3048)
			(end 0.120396 0.3048)
			(stroke
				(width 0.1)
				(type default)
			)
			(layer "F.Fab")
		)
		(fp_line
			(start -0.12065 0.2794)
			(end -0.12065 0.3048)
			(stroke
				(width 0.1)
				(type default)
			)
			(layer "F.Fab")
		)
		(fp_line
			(start 0.120396 0.2794)
			(end -0.12065 0.2794)
			(stroke
				(width 0.1)
				(type default)
			)
			(layer "F.Fab")
		)
		(fp_line
			(start -0.12065 -0.2794)
			(end 0.12065 -0.2794)
			(stroke
				(width 0.1)
				(type default)
			)
			(layer "F.Fab")
		)
		(fp_line
			(start 0.12065 -0.2794)
			(end 0.12065 -0.3048)
			(stroke
				(width 0.1)
				(type default)
			)
			(layer "F.Fab")
		)
		(fp_line
			(start 0.12065 -0.3048)
			(end 0.67945 -0.3048)
			(stroke
				(width 0.1)
				(type default)
			)
			(layer "F.Fab")
		)
		(fp_line
			(start 0.67945 -0.3048)
			(end 0.67945 0.3048)
			(stroke
				(width 0.1)
				(type default)
			)
			(layer "F.Fab")
		)
		(fp_line
			(start -0.67945 -0.305054)
			(end -0.12065 -0.305054)
			(stroke
				(width 0.1)
				(type default)
			)
			(layer "F.Fab")
		)
		(fp_line
			(start -0.12065 -0.305054)
			(end -0.12065 -0.2794)
			(stroke
				(width 0.1)
				(type default)
			)
			(layer "F.Fab")
		)
		(pad "1" smd circle
			(at -0.40005 0 270)
			(size 0 0)
			(layers "F.Cu" "F.Mask" "F.Paste")
			(net "P1V25_SERDES_VDDPLL_PEX1")
		)
		(pad "2" smd circle
			(at 0.40005 0 270)
			(size 0 0)
			(layers "F.Cu" "F.Mask" "F.Paste")
			(net "P1V25_SERDES_VDDPLL_PEX1_C2")
		)
	)
	(footprint ""
		(layer "F.Cu")
		(at 262.461756 -311.007252 -135)
		(property "Reference" "R1393"
			(at 0 0 225)
			(layer "F.SilkS")
			(hide yes)
			(effects
				(font
					(size 1.27 1.27)
				)
			)
		)
		(property "Value" ""
			(at 0 0 225)
			(layer "F.Fab")
			(effects
				(font
					(size 1.27 1.27)
				)
			)
		)
		(duplicate_pad_numbers_are_jumpers no)
		(fp_line
			(start 0.787389 0.406267)
			(end -0.787389 0.406267)
			(stroke
				(width 0.1524)
				(type default)
			)
			(layer "F.SilkS")
		)
		(fp_line
			(start 0.787389 -0.406267)
			(end 0.787389 0.406267)
			(stroke
				(width 0.1524)
				(type default)
			)
			(layer "F.SilkS")
		)
		(fp_line
			(start -0.787389 0.406267)
			(end -0.787389 -0.406267)
			(stroke
				(width 0.1524)
				(type default)
			)
			(layer "F.SilkS")
		)
		(fp_line
			(start -0.787389 -0.406267)
			(end 0.787389 -0.406267)
			(stroke
				(width 0.1524)
				(type default)
			)
			(layer "F.SilkS")
		)
		(fp_line
			(start 0.679446 0.30479)
			(end 0.120515 0.30479)
			(stroke
				(width 0.1)
				(type default)
			)
			(layer "F.Fab")
		)
		(fp_line
			(start 0.120515 0.30479)
			(end 0.120335 0.279466)
			(stroke
				(width 0.1)
				(type default)
			)
			(layer "F.Fab")
		)
		(fp_line
			(start 0.120335 0.279466)
			(end -0.120695 0.279466)
			(stroke
				(width 0.1)
				(type default)
			)
			(layer "F.Fab")
		)
		(fp_line
			(start 0.679446 -0.30479)
			(end 0.679446 0.30479)
			(stroke
				(width 0.1)
				(type default)
			)
			(layer "F.Fab")
		)
		(fp_line
			(start -0.120515 0.30479)
			(end -0.679446 0.30479)
			(stroke
				(width 0.1)
				(type default)
			)
			(layer "F.Fab")
		)
		(fp_line
			(start -0.120695 0.279466)
			(end -0.120515 0.30479)
			(stroke
				(width 0.1)
				(type default)
			)
			(layer "F.Fab")
		)
		(fp_line
			(start 0.120695 -0.279466)
			(end 0.120515 -0.30479)
			(stroke
				(width 0.1)
				(type default)
			)
			(layer "F.Fab")
		)
		(fp_line
			(start 0.120515 -0.30479)
			(end 0.679446 -0.30479)
			(stroke
				(width 0.1)
				(type default)
			)
			(layer "F.Fab")
		)
		(fp_line
			(start -0.679446 0.30479)
			(end -0.679446 -0.305149)
			(stroke
				(width 0.1)
				(type default)
			)
			(layer "F.Fab")
		)
		(fp_line
			(start -0.120695 -0.279466)
			(end 0.120695 -0.279466)
			(stroke
				(width 0.1)
				(type default)
			)
			(layer "F.Fab")
		)
		(fp_line
			(start -0.120695 -0.304969)
			(end -0.120695 -0.279466)
			(stroke
				(width 0.1)
				(type default)
			)
			(layer "F.Fab")
		)
		(fp_line
			(start -0.679446 -0.305149)
			(end -0.120695 -0.304969)
			(stroke
				(width 0.1)
				(type default)
			)
			(layer "F.Fab")
		)
		(pad "1" smd circle
			(at -0.40005 0 225)
			(size 0 0)
			(layers "F.Cu" "F.Mask" "F.Paste")
			(net "PU_PEX2_PAD_TRI_L")
		)
		(pad "2" smd circle
			(at 0.40005 0 225)
			(size 0 0)
			(layers "F.Cu" "F.Mask" "F.Paste")
			(net "P1V8_PEX")
		)
	)
)
